FILE_TYPE = MULTI_PHYS_TABLE;

PART 'RAA229621GNPHA0'

{========================================================================================}
:VALUE              | PART_TYPE | MATERIAL | PART_NUMBER    = STANDARD        | LIFECYCLE     | PART_NUMBER   | JEDEC_TYPE           | DESCRIPTION                                                            | MANUFTR | MANUF_PN           | RD_CMPLS_LVL | CMPLS_LVL | FROM_PJ       | CLASS | DIP_SMD | DATA                                        | EE_CHECK_LIST | FP_ECN | PSL | CREATOR | STATUS | MSD  | ESD_CDM | ESD_HBM | ESD_MM | PIN_LENGTH_SHORT_PIN | PIN_LENGTH_LONG_PIN | CREATEDAY  ;
{========================================================================================}
 'RAA229621GNP#HA0' | 'SMLF'    | 'IC'     | 'AL229621000'(!) = ''              | ''            | 'AL229621000' |'QFN40_TH_0-4_5X5XE'| 'IC(40P)RAA229621GNP#HA0(QFN)'                                         | 'RTT'   | 'RAA229621GNP#HA0' | 'EP(V1)'     | ''        | 'S5N-YC'      | 'IC'  | ''      | 'RTT_RAA229621GNPHA0.pdf'                   | ''            | ''     | ''  | ''      | ''     | 'NA' | 'NA'    | 'NA'    | 'NA'   | '0 MILS'             | '0 MILS'            | '20201118'
 'RAA229621GNP#HA0' | 'SMLF'    | 'EMPTY'  | 'AL229621000'(!) = ''              | ''            | 'AL229621000' |'QFN40_TH_0-4_5X5XE'| 'IC(40P)RAA229621GNP#HA0(QFN)'                                         | 'RTT'   | 'RAA229621GNP#HA0' | 'EP(V1)'     | ''        | 'S5N-YC'      | 'IC'  | ''      | 'RTT_RAA229621GNPHA0.pdf'                   | ''            | ''     | ''  | ''      | ''     | 'NA' | 'NA'    | 'NA'    | 'NA'   | '0 MILS'             | '0 MILS'            | '20201118'
 'RAA229621GNP#HA0' | 'SMLF'    | 'IC'     | 'AR0S6ZPS001'(!) = ''              | ''            | 'AR0S6ZPS001' |'QFN40_TH_0-4_5X5XE'| 'PROG IC(41P)RAA229621GNP#HA0(QFN) (checksum:2ABE1654/1A270A85)'       | 'RTT'   | 'RAA229621GNP#HA0' | 'EP(V1)'     | ''        | 'S6Z-OSCAR'   | 'IC'  | ''      | 'RTT_RAA229621GNPHA0_2ABE1654_1A270A85.pdf' | ''            | ''     | ''  | ''      | ''     | ''   | ''      | ''      | ''     | '0 MILS'             | '0 MILS'            | '20210708'
 'RAA229621GNP#HA0' | 'SMLF'    | 'EMPTY'  | 'AR0S6ZPS001'(!) = ''              | ''            | 'AR0S6ZPS001' |'QFN40_TH_0-4_5X5XE'| 'PROG IC(41P)RAA229621GNP#HA0(QFN) (checksum:2ABE1654/1A270A85)'       | 'RTT'   | 'RAA229621GNP#HA0' | 'EP(V1)'     | ''        | 'S6Z-OSCAR'   | 'IC'  | ''      | 'RTT_RAA229621GNPHA0_2ABE1654_1A270A85.pdf' | ''            | ''     | ''  | ''      | ''     | ''   | ''      | ''      | ''     | '0 MILS'             | '0 MILS'            | '20210708'
 'RAA229621GNP#HA0' | 'SMLF'    | 'IC'     | 'AR0T6GPV004'(!) = ''              | ''            | 'AR0T6GPV004' |'QFN40_TH_0-4_5X5XE'| 'PROG IC(41P)RAA229621GNP#HA0(QFN) (checksum:8A949CD9)'                | 'RTT'   | 'RAA229621GNP#HA0' | 'EP(V1)'     | ''        | 'T6G-OSCAR'   | 'IC'  | ''      | 'RTT_RAA229621GNPHA0_8A949CD9.pdf'          | ''            | ''     | ''  | ''      | ''     | ''   | ''      | ''      | ''     | '0 MILS'             | '0 MILS'            | '20210729'
 'RAA229621GNP#HA0' | 'SMLF'    | 'EMPTY'  | 'AR0T6GPV004'(!) = ''              | ''            | 'AR0T6GPV004' |'QFN40_TH_0-4_5X5XE'| 'PROG IC(41P)RAA229621GNP#HA0(QFN) (checksum:8A949CD9)'                | 'RTT'   | 'RAA229621GNP#HA0' | 'EP(V1)'     | ''        | 'T6G-OSCAR'   | 'IC'  | ''      | 'RTT_RAA229621GNPHA0_8A949CD9.pdf'          | ''            | ''     | ''  | ''      | ''     | ''   | ''      | ''      | ''     | '0 MILS'             | '0 MILS'            | '20210729'
 'RAA229621GNP#HA0' | 'SMLF'    | 'IC'     | 'AR0S6ZPS014'(!) = ''              | ''            | 'AR0S6ZPS014' |'QFN40_TH_0-4_5X5XE'| 'PROG IC(41P)RAA229621GNP#HA0(QFN) (checksum:75CB6802/738B3B18)'       | 'RTT'   | 'RAA229621GNP#HA0' | 'EP(V1)'     | 'EP(V1)'  | 'S6Z-NINA'    | 'IC'  | ''      | 'RTT_RAA229621GNPHA0_75CB6802_738B3B18.pdf' | ''            | ''     | ''  | ''      | ''     | ''   | ''      | ''      | ''     | '0 MILS'             | '0 MILS'            | '20211025'
 'RAA229621GNP#HA0' | 'SMLF'    | 'EMPTY'  | 'AR0S6ZPS014'(!) = ''              | ''            | 'AR0S6ZPS014' |'QFN40_TH_0-4_5X5XE'| 'PROG IC(41P)RAA229621GNP#HA0(QFN) (checksum:75CB6802/738B3B18)'       | 'RTT'   | 'RAA229621GNP#HA0' | 'EP(V1)'     | 'EP(V1)'  | 'S6Z-NINA'    | 'IC'  | ''      | 'RTT_RAA229621GNPHA0_75CB6802_738B3B18.pdf' | ''            | ''     | ''  | ''      | ''     | ''   | ''      | ''      | ''     | '0 MILS'             | '0 MILS'            | '20211025'
 'RAA229621GNP#HA0' | 'SMLF'    | 'IC'     | 'AR0T6GPV006'(!) = ''              | ''            | 'AR0T6GPV006' |'QFN40_TH_0-4_5X5XE'| 'PROG IC(41P)RAA229621GNP#HA0(QFN) (checksum:DE3C691B)'                | 'RTT'   | 'RAA229621GNP#HA0' | 'EP(V1)'     | 'EP(V1)'  | 'T6G-NINA'    | 'IC'  | ''      | 'RTT_RAA229621GNPHA0_DE3C691B.pdf'          | ''            | ''     | ''  | ''      | ''     | ''   | ''      | ''      | ''     | '0 MILS'             | '0 MILS'            | '20211025'
 'RAA229621GNP#HA0' | 'SMLF'    | 'EMPTY'  | 'AR0T6GPV006'(!) = ''              | ''            | 'AR0T6GPV006' |'QFN40_TH_0-4_5X5XE'| 'PROG IC(41P)RAA229621GNP#HA0(QFN) (checksum:DE3C691B)'                | 'RTT'   | 'RAA229621GNP#HA0' | 'EP(V1)'     | 'EP(V1)'  | 'T6G-NINA'    | 'IC'  | ''      | 'RTT_RAA229621GNPHA0_DE3C691B.pdf'          | ''            | ''     | ''  | ''      | ''     | ''   | ''      | ''      | ''     | '0 MILS'             | '0 MILS'            | '20211025'
 'RAA229621GNP#HA0' | 'SMLF'    | 'IC'     | 'AR0A5GP6004'(!) = ''              | ''            | 'AR0A5GP6004' |'QFN40_TH_0-4_5X5XE'| 'PROG IC(41P)RAA229621GNP#HA0(QFN) (checksum:08230BA3)'                | 'RTT'   | 'RAA229621GNP#HA0' | 'EP(V1)'     | 'EP(V1)'  | 'A5G-OSCAR'   | 'IC'  | ''      | 'RTT_RAA229621GNPHA0_08230BA3.pdf'          | ''            | ''     | ''  | ''      | ''     | ''   | ''      | ''      | ''     | '0 MILS'             | '0 MILS'            | '20211201'
 'RAA229621GNP#HA0' | 'SMLF'    | 'EMPTY'  | 'AR0A5GP6004'(!) = ''              | ''            | 'AR0A5GP6004' |'QFN40_TH_0-4_5X5XE'| 'PROG IC(41P)RAA229621GNP#HA0(QFN) (checksum:08230BA3)'                | 'RTT'   | 'RAA229621GNP#HA0' | 'EP(V1)'     | 'EP(V1)'  | 'A5G-OSCAR'   | 'IC'  | ''      | 'RTT_RAA229621GNPHA0_08230BA3.pdf'          | ''            | ''     | ''  | ''      | ''     | ''   | ''      | ''      | ''     | '0 MILS'             | '0 MILS'            | '20211201'
 'RAA229621GNP#HA0' | 'SMLF'    | 'IC'     | 'AR0T6GPV009'(!) = ''              | ''            | 'AR0T6GPV009' |'QFN40_TH_0-4_5X5XE'| 'PROG IC(41P)RAA229621GNP#HA0(QFN) (checksum:6BC9C55F)'                | 'RTT'   | 'RAA229621GNP#HA0' | 'EP(V1)'     | 'EP(V1)'  | 'T6G-DAVID'   | 'IC'  | ''      | 'RTT_RAA229621GNPHA0_6BC9C55F.pdf'          | ''            | ''     | ''  | ''      | ''     | ''   | ''      | ''      | ''     | '0 MILS'             | '0 MILS'            | '20220302'
 'RAA229621GNP#HA0' | 'SMLF'    | 'EMPTY'  | 'AR0T6GPV009'(!) = ''              | ''            | 'AR0T6GPV009' |'QFN40_TH_0-4_5X5XE'| 'PROG IC(41P)RAA229621GNP#HA0(QFN) (checksum:6BC9C55F)'                | 'RTT'   | 'RAA229621GNP#HA0' | 'EP(V1)'     | 'EP(V1)'  | 'T6G-DAVID'   | 'IC'  | ''      | 'RTT_RAA229621GNPHA0_6BC9C55F.pdf'          | ''            | ''     | ''  | ''      | ''     | ''   | ''      | ''      | ''     | '0 MILS'             | '0 MILS'            | '20220302'
 'RAA229621GNP#HA0' | 'SMLF'    | 'IC'     | 'ARF0TGP4001'(!) = ''              | ''            | 'ARF0TGP4001' |'QFN40_TH_0-4_5X5XE'| 'PROG IC(41P)RAA229621GNP#HA0(QFN) (checksum:83DFB166)'                | 'RTT'   | 'RAA229621GNP#HA0' | 'EP(V1)'     | 'EP(V1)'  | 'F0TG-CART'   | 'IC'  | ''      | 'RTT_RAA229621GNPHA0_83DFB166.pdf'          | ''            | ''     | ''  | ''      | ''     | ''   | ''      | ''      | ''     | '0 MILS'             | '0 MILS'            | '20220615'
 'RAA229621GNP#HA0' | 'SMLF'    | 'EMPTY'  | 'ARF0TGP4001'(!) = ''              | ''            | 'ARF0TGP4001' |'QFN40_TH_0-4_5X5XE'| 'PROG IC(41P)RAA229621GNP#HA0(QFN) (checksum:83DFB166)'                | 'RTT'   | 'RAA229621GNP#HA0' | 'EP(V1)'     | 'EP(V1)'  | 'F0TG-CART'   | 'IC'  | ''      | 'RTT_RAA229621GNPHA0_83DFB166.pdf'          | ''            | ''     | ''  | ''      | ''     | ''   | ''      | ''      | ''     | '0 MILS'             | '0 MILS'            | '20220615'
 'RAA229621GNP#HA0' | 'SMLF'    | 'IC'     | 'AR0MF6P2004'(!) = ''              | ''            | 'AR0MF6P2004' |'QFN40_TH_0-4_5X5XE'| 'PROG IC(41P)RAA229621GNP#HA0(QFN)SELASN (checksum:23633041/984D24A3)' | 'RTT'   | 'RAA229621GNP#HA0' | 'EP(V1)'     | 'EP(V1)'  | 'MF6-WILLIAM' | 'IC'  | ''      | 'RTT_RAA229621GNPHA0_23633041_984D24A3.pdf' | ''            | ''     | ''  | ''      | ''     | ''   | ''      | ''      | ''     | '0 MILS'             | '0 MILS'            | '20220912'
 'RAA229621GNP#HA0' | 'SMLF'    | 'EMPTY'  | 'AR0MF6P2004'(!) = ''              | ''            | 'AR0MF6P2004' |'QFN40_TH_0-4_5X5XE'| 'PROG IC(41P)RAA229621GNP#HA0(QFN)SELASN (checksum:23633041/984D24A3)' | 'RTT'   | 'RAA229621GNP#HA0' | 'EP(V1)'     | 'EP(V1)'  | 'MF6-WILLIAM' | 'IC'  | ''      | 'RTT_RAA229621GNPHA0_23633041_984D24A3.pdf' | ''            | ''     | ''  | ''      | ''     | ''   | ''      | ''      | ''     | '0 MILS'             | '0 MILS'            | '20220912'
 'RAA229621GNP#HA0' | 'SMLF'    | 'IC'     | 'AR0S6ZPS016'(!) = ''              | ''            | 'AR0S6ZPS016' |'QFN40_TH_0-4_5X5XE'| 'PROG IC(41P)RAA229621GNP#HA0(QFN) (checksum:9950FFD9/BF193B06)'       | 'RTT'   | 'RAA229621GNP#HA0' | 'EP(V1)'     | 'EP(V1)'  | 'S6Z-DAVID'   | 'IC'  | ''      | 'RTT_RAA229621GNPHA0_9950FFD9_BF193B06.pdf' | ''            | ''     | ''  | ''      | ''     | ''   | ''      | ''      | ''     | '0 MILS'             | '0 MILS'            | '20221114'
 'RAA229621GNP#HA0' | 'SMLF'    | 'EMPTY'  | 'AR0S6ZPS016'(!) = ''              | ''            | 'AR0S6ZPS016' |'QFN40_TH_0-4_5X5XE'| 'PROG IC(41P)RAA229621GNP#HA0(QFN) (checksum:9950FFD9/BF193B06)'       | 'RTT'   | 'RAA229621GNP#HA0' | 'EP(V1)'     | 'EP(V1)'  | 'S6Z-DAVID'   | 'IC'  | ''      | 'RTT_RAA229621GNPHA0_9950FFD9_BF193B06.pdf' | ''            | ''     | ''  | ''      | ''     | ''   | ''      | ''      | ''     | '0 MILS'             | '0 MILS'            | '20221114'
 'RAA229621GNP#HA0' | 'SMLF'    | 'IC'     | 'ARF0TGP4003'(!) = ''              | ''            | 'ARF0TGP4003' |'QFN40_TH_0-4_5X5XE'| 'PROG IC(41P)RAA229621GNP#HA0(QFN) (checksum:B68CAFAB)'                | 'RTT'   | 'RAA229621GNP#HA0' | 'EP(V1)'     | 'EP(V1)'  | 'F0TG-CART'   | 'IC'  | ''      | 'RTT_RAA229621GNPHA0_B68CAFAB.pdf'          | ''            | ''     | ''  | ''      | ''     | ''   | ''      | ''      | ''     | '0 MILS'             | '0 MILS'            | '20221212'
 'RAA229621GNP#HA0' | 'SMLF'    | 'EMPTY'  | 'ARF0TGP4003'(!) = ''              | ''            | 'ARF0TGP4003' |'QFN40_TH_0-4_5X5XE'| 'PROG IC(41P)RAA229621GNP#HA0(QFN) (checksum:B68CAFAB)'                | 'RTT'   | 'RAA229621GNP#HA0' | 'EP(V1)'     | 'EP(V1)'  | 'F0TG-CART'   | 'IC'  | ''      | 'RTT_RAA229621GNPHA0_B68CAFAB.pdf'          | ''            | ''     | ''  | ''      | ''     | ''   | ''      | ''      | ''     | '0 MILS'             | '0 MILS'            | '20221212'
 'RAA229621GNP#HA0' | 'SMLF'    | 'IC'     | 'AR0MF6P2010'(!) = ''              | ''            | 'AR0MF6P2010' |'QFN40_TH_0-4_5X5XE'| 'PROG IC(41P)RAA229621GNP#HA0 SELASN (cheksum:7746253B/98E82766)'      | 'RTT'   | 'RAA229621GNP#HA0' | 'EP(V1)'     | 'EP(V1)'  | 'MF6-WILLIAM' | 'IC'  | ''      | 'RTT_RAA229621GNPHA0_7746253B_98E82766.pdf' | ''            | ''     | ''  | ''      | ''     | ''   | ''      | ''      | ''     | '0 MILS'             | '0 MILS'            | '20230221'
 'RAA229621GNP#HA0' | 'SMLF'    | 'EMPTY'  | 'AR0MF6P2010'(!) = ''              | ''            | 'AR0MF6P2010' |'QFN40_TH_0-4_5X5XE'| 'PROG IC(41P)RAA229621GNP#HA0 SELASN (cheksum:7746253B/98E82766)'      | 'RTT'   | 'RAA229621GNP#HA0' | 'EP(V1)'     | 'EP(V1)'  | 'MF6-WILLIAM' | 'IC'  | ''      | 'RTT_RAA229621GNPHA0_7746253B_98E82766.pdf' | ''            | ''     | ''  | ''      | ''     | ''   | ''      | ''      | ''     | '0 MILS'             | '0 MILS'            | '20230221'
 'RAA229621GNP#HA0' | 'SMLF'    | 'IC'     | 'AR0MF6P2014'(!) = ''              | ''            | 'AR0MF6P2014' |'QFN40_TH_0-4_5X5XE'| 'PROG IC(41P) RAA229621GNP#HA0 SELASN (cheksum:C1DCBC44/98E82766)'     | 'RTT'   | 'RAA229621GNP#HA0' | 'EP(V1)'     | 'EP(V1)'  | 'MF6-WILLIAM' | 'IC'  | ''      | 'RTT_RAA229621GNPHA0_C1DCBC44_98E82766.pdf' | ''            | ''     | ''  | ''      | ''     | ''   | ''      | ''      | ''     | '0 MILS'             | '0 MILS'            | '20230306'
 'RAA229621GNP#HA0' | 'SMLF'    | 'EMPTY'  | 'AR0MF6P2014'(!) = ''              | ''            | 'AR0MF6P2014' |'QFN40_TH_0-4_5X5XE'| 'PROG IC(41P) RAA229621GNP#HA0 SELASN (cheksum:C1DCBC44/98E82766)'     | 'RTT'   | 'RAA229621GNP#HA0' | 'EP(V1)'     | 'EP(V1)'  | 'MF6-WILLIAM' | 'IC'  | ''      | 'RTT_RAA229621GNPHA0_C1DCBC44_98E82766.pdf' | ''            | ''     | ''  | ''      | ''     | ''   | ''      | ''      | ''     | '0 MILS'             | '0 MILS'            | '20230306'
 'RAA229621GNP#HA0' | 'SMLF'    | 'IC'     | 'AR0MF6P2017'(!) = ''              | ''            | 'AR0MF6P2017' |'QFN40_TH_0-4_5X5XE'| 'PROG IC(41P)RAA229621GNP#HA0(QFN) (checksum:0370FEC9/98E82766)'       | 'RTT'   | 'RAA229621GNP#HA0' | 'EP(V1)'     | 'EP(V1)'  | 'MF6-WILLIAM' | 'IC'  | ''      | 'RTT_RAA229621GNPHA0_0370FEC9_98E82766.pdf' | ''            | ''     | ''  | ''      | ''     | ''   | ''      | ''      | ''     | '0 MILS'             | '0 MILS'            | '20230411'
 'RAA229621GNP#HA0' | 'SMLF'    | 'EMPTY'  | 'AR0MF6P2017'(!) = ''              | ''            | 'AR0MF6P2017' |'QFN40_TH_0-4_5X5XE'| 'PROG IC(41P)RAA229621GNP#HA0(QFN) (checksum:0370FEC9/98E82766)'       | 'RTT'   | 'RAA229621GNP#HA0' | 'EP(V1)'     | 'EP(V1)'  | 'MF6-WILLIAM' | 'IC'  | ''      | 'RTT_RAA229621GNPHA0_0370FEC9_98E82766.pdf' | ''            | ''     | ''  | ''      | ''     | ''   | ''      | ''      | ''     | '0 MILS'             | '0 MILS'            | '20230411'
 'RAA229621GNP#HA0' | 'SMLF'    | 'IC'     | 'AR0MF6P2021'(!) = ''              | ''            | 'AR0MF6P2021' |'QFN40_TH_0-4_5X5XE'| 'PROG IC(41P) RAA229621GNP#HA0 (QFN) (checksum:F0255FE7/98E82766)'     | 'RTT'   | 'RAA229621GNP#HA0' | 'EP(V1)'     | 'EP(V1)'  | 'MF6-WILLIAM' | 'IC'  | ''      | 'RTT_RAA229621GNPHA0_F0255FE7_98E82766.pdf' | ''            | ''     | ''  | ''      | ''     | ''   | ''      | ''      | ''     | '0 MILS'             | '0 MILS'            | '20230731'
 'RAA229621GNP#HA0' | 'SMLF'    | 'EMPTY'  | 'AR0MF6P2021'(!) = ''              | ''            | 'AR0MF6P2021' |'QFN40_TH_0-4_5X5XE'| 'PROG IC(41P) RAA229621GNP#HA0 (QFN) (checksum:F0255FE7/98E82766)'     | 'RTT'   | 'RAA229621GNP#HA0' | 'EP(V1)'     | 'EP(V1)'  | 'MF6-WILLIAM' | 'IC'  | ''      | 'RTT_RAA229621GNPHA0_F0255FE7_98E82766.pdf' | ''            | ''     | ''  | ''      | ''     | ''   | ''      | ''      | ''     | '0 MILS'             | '0 MILS'            | '20230731'
 'RAA229621GNP#HA0' | 'SMLF'    | 'IC'     | 'AR0MF6P2024'(!) = ''               | ''               | 'AR0MF6P2024' |'QFN40_TH_0-4_5X5XE'| 'PROG IC(41P)RAA229621GNP#HA0(QFN) (checksum:6CD32CB5/980BE0BB)'       | 'RTT'   | 'RAA229621GNP#HA0' | 'EP(V1)'     | ''        | 'MF6-WILLIAM' | 'IC'  | ''      | 'RTT_RAA229621GNPHA0_6CD32CB5_980BE0BB.pdf' | ''            | ''     | ''  | ''      | ''     | ''   | ''      | ''      | ''     | '0 MILS'             | '0 MILS'            | '20230809'
 'RAA229621GNP#HA0' | 'SMLF'    | 'EMPTY'  | 'AR0MF6P2024'(!) = ''               | ''               | 'AR0MF6P2024' |'QFN40_TH_0-4_5X5XE'| 'PROG IC(41P)RAA229621GNP#HA0(QFN) (checksum:6CD32CB5/980BE0BB)'       | 'RTT'   | 'RAA229621GNP#HA0' | 'EP(V1)'     | ''        | 'MF6-WILLIAM' | 'IC'  | ''      | 'RTT_RAA229621GNPHA0_6CD32CB5_980BE0BB.pdf' | ''            | ''     | ''  | ''      | ''     | ''   | ''      | ''      | ''     | '0 MILS'             | '0 MILS'            | '20230809'

END_PART

END.

